# S9S_MB_2U (Grand Teton) — schematic parts with pin connectivity, parts 3225–3356 of 6093; source: Cadence DE-HDL packaged netlist (pstxprt.dat, pstxnet.dat, pstchip.dat)

Q141  BC847BPN  IC  pkg SOT363XB  page 123
  1  E1  BI  = GND
  2  B1  IN  = H_CPU0_MEMTRIP_R
  3  C2  BI  = H_CPU0_MEMTRIP
  4  E2  BI  = PVNN_TERM_CPU0
  5  B2  IN  = H_CPU0_MEMTRIP_OUT_VT_R_N
  6  C1  BI  = H_CPU0_MEMTRIP_VT_N

Q142  BC847BPN  IC  pkg SOT363XB  page 122
  1  E1  BI  = GND
  2  B1  IN  = H_CPU1_MEMHOT_OUT_R
  3  C2  BI  = H_CPU1_MEMHOT_OUT
  4  E2  BI  = PVNN_TERM_CPU1
  5  B2  IN  = H_CPU1_MEMHOT_OUT_VT_R_N
  6  C1  BI  = H_CPU1_MEMHOT_OUT_VT_N

Q143  BC847BPN  IC  pkg SOT363XB  page 122
  1  E1  BI  = GND
  2  B1  IN  = H_CPU0_MEMHOT_OUT_R
  3  C2  BI  = H_CPU0_MEMHOT_OUT
  4  E2  BI  = PVNN_TERM_CPU0
  5  B2  IN  = H_CPU0_MEMHOT_OUT_VT_R_N
  6  C1  BI  = H_CPU0_MEMHOT_OUT_VT_N

Q144  MOSFET_NCH_DUAL  PJT138K IC  pkg SOT363XD  page 224
  1  S1  BI  = GND
  2  G1  BI  = PWRGD_PS_PWROK_PLD
  3  D2  BI  = PWRGD_PS_PWROK_PLD_ISO
  4  S2  BI  = GND
  5  G2  BI  = PWRGD_PS_PWROK_PLD_N
  6  D1  BI  = PWRGD_PS_PWROK_PLD_N

Q145  MOSFET_NCH_DUAL  PJT138K IC  pkg SOT363XD  page 246
  1  S1  BI  = GND
  2  G1  BI  = HPDB_HSC_PWRGD
  3  D2  BI  = HPDB_HSC_PWRGD_ISO
  4  S2  BI  = GND
  5  G2  BI  = HPDB_HSC_PWRGD_N
  6  D1  BI  = HPDB_HSC_PWRGD_N

Q146  MOSFET_NCH_DUAL  PJT138K IC  pkg SOT363XD  page 146
  1  S1  BI  = GND
  2  G1  BI  = SWB_HSC_PWRGD
  3  D2  BI  = SWB_HSC_PWRGD_ISO
  4  S2  BI  = GND
  5  G2  BI  = SWB_HSC_PWRGD_N
  6  D1  BI  = SWB_HSC_PWRGD_N

Q148  MOSFET_NCH_DUAL  PJT138K IC  pkg SOT363XD  page 145
  1  S1  BI  = GND
  2  G1  BI  = HGX_DETECT_N
  3  D2  BI  = HGX_DETECT_N_ISO
  4  S2  BI  = GND
  5  G2  BI  = HGX_DETECT
  6  D1  BI  = HGX_DETECT

Q150  MOSFET_NCH_DUAL  PJT138K IC  pkg SOT363XD  page 255
  1  S1  BI  = GND
  2  G1  BI  = P12V_SCM_FAULT_R_N
  3  D2  BI  = LED_P12V_SCM_FAULT_D2
  4  S2  BI  = GND
  5  G2  BI  = LED_P12V_SCM_FAULT_D1
  6  D1  BI  = LED_P12V_SCM_FAULT_D1

Q151  MOSFET_NCH_DUAL  PJT138K IC  pkg SOT363XD  page 144
  1  S1  BI  = GND
  2  G1  BI  = PRSNT_SWB_N
  3  D2  BI  = PRSNT_SWB_ISO_N
  4  S2  BI  = GND
  5  G2  BI  = PRSNT_SWB
  6  D1  BI  = PRSNT_SWB

Q152  MOSFET_NCH_DUAL  PJT138K IC  pkg SOT363XD  page 144
  1  S1  BI  = GND
  2  G1  BI  = PRSNT_CABLE_SWB_B2_N
  3  D2  BI  = PRSNT_CABLE_SWB_B2_ISO_N
  4  S2  BI  = GND
  5  G2  BI  = PRSNT_CABLE_SWB_B2
  6  D1  BI  = PRSNT_CABLE_SWB_B2

Q153  MOSFET_NCH_DUAL  PJT138K IC  pkg SOT363XD  page 144
  1  S1  BI  = GND
  2  G1  BI  = PRSNT_CABLE_SWB_B1_N
  3  D2  BI  = PRSNT_CABLE_SWB_B1_ISO_N
  4  S2  BI  = GND
  5  G2  BI  = PRSNT_CABLE_SWB_B1
  6  D1  BI  = PRSNT_CABLE_SWB_B1

Q154  MOSFET_NCH_DUAL  PJT138K IC  pkg SOT363XD  page 144
  1  S1  BI  = GND
  2  G1  BI  = PRSNT_CABLE_GPU_A3_N
  3  D2  BI  = PRSNT_CABLE_GPU_A3_ISO_N
  4  S2  BI  = GND
  5  G2  BI  = PRSNT_CABLE_GPU_A3
  6  D1  BI  = PRSNT_CABLE_GPU_A3

Q236  MOSFET_NCH_DUAL  PJT138K IC  pkg SOT363XD  page 260
  1  S1  BI  = GND
  2  G1  BI  = PWRGD_P5V
  3  D2  BI  = PWRGD_P5V_ISO
  4  S2  BI  = GND
  5  G2  BI  = PWRGD_P5V_N
  6  D1  BI  = PWRGD_P5V_N

R1  Q_RES  10 1% CHIP  pkg 0402LF  page 13 : 1 = H_CPU_PRDY_QS_GTL_N ; 2 = H_CPU0_PRDY_QS_GTL_R_N
R2  Q_RES  100 1% CHIP  pkg 0402LF  page 13 : 1 = H_CPU_PREQ_QS_GTL_N ; 2 = H_CPU0_PREQ_QS_GTL_R_N
R3  Q_RES  33.2 1% CHIP  pkg 0402LF  page 13 : 1 = PECI_CPU_GTL ; 2 = PECI_CPU0_GTL_R
R4  Q_RES  200 1% CHIP  pkg 0402LF  page 13 : 1 = JTAG_MUX_CPU0_GTL_TDI ; 2 = JTAG_DBP_CPU0_GTL_R_TDI
R5  Q_RES  100 1% CHIP  pkg 0402LF  page 13 : 1 = JTAG_DBP_CPU_GTL_TCK ; 2 = JTAG_DBP_CPU0_GTL_R_TCK
R6  Q_RES  100 1% CHIP  pkg 0402LF  page 13 : 1 = JTAG_DBP_CPU_QS_GTL_TMS ; 2 = JTAG_DBP_CPU0_QS_GTL_R_TMS
R7  Q_RES  33.2 1% CHIP  pkg 0402LF  page 14 : 1 = H_CPU0_PMDOWN_PCH_R ; 2 = H_CPU0_PMDOWN_PCH
R8  Q_RES  10K 1% CHIP  pkg 0402LF  page 204 : 1 = P3V3_AUX ; 2 = FM_PS_PWROK_DLY_R_SEL
R10  Q_RES  33.2 1% CHIP  pkg 0402LF  page 14 : 1 = H_CPU0_PMSYNC_PCH_R ; 2 = H_CPU0_PMSYNC_PCH
R11  Q_RES  33.2 1% CHIP  pkg 0402LF  page 14 : 1 = H_CPU0_PMDOWN_CPU1_R1 ; 2 = H_CPU0_PMDOWN_CPU1
R12  Q_RES  0 5% CHIP  pkg 0402LF  page 14 : 1 = SVID_DIO0_CPU0 ; 2 = SVID_DIO0_CPU0_R
R13  Q_RES  0 5% CHIP  pkg 0402LF  page 14 : 1 = SVID_CLK0_CPU0 ; 2 = SVID_CLK0_CPU0_R
R14  Q_RES  200 1% CHIP  pkg 0402LF  page 14 : 1 = SVID_ALERT0_CPU0_N ; 2 = SVID_ALERT0_CPU0_R_N
R15  Q_RES  0 5% CHIP  pkg 0402LF  page 14 : 1 = SVID_DIO1_CPU0 ; 2 = SVID_DIO1_CPU0_R
R16  Q_RES  0 5% CHIP  pkg 0402LF  page 14 : 1 = SVID_CLK1_CPU0 ; 2 = SVID_CLK1_CPU0_R
R17  Q_RES  200 1% CHIP  pkg 0402LF  page 14 : 1 = SVID_ALERT1_CPU0_N ; 2 = SVID_ALERT1_CPU0_R_N
R18  Q_RES  499 1% CHIP  pkg 0402LF  page 16 : 1 = PVNN_TERM_CPU0 ; 2 = DBP_CPU_MBP0_GTL_N
R19  Q_RES  499 1% CHIP  pkg 0402LF  page 16 : 1 = PVNN_TERM_CPU0 ; 2 = DBP_CPU_MBP1_GTL_N
R20  Q_RES  0 5% CHIP  pkg 0402LF  page 16 : 1 = DBP_CPU_MBP0_GTL_N ; 2 = FM_PCH_TRIGGER0_N
R21  Q_RES  0 5% CHIP  pkg 0402LF  page 16 : 1 = DBP_CPU_MBP1_GTL_N ; 2 = FM_PCH_TRIGGER1_N
R22  Q_RES  100 1% CHIP  pkg 0402LF  page 16 : 1 = DBP_CPU0_MBP0_GTL_R_N ; 2 = DBP_CPU_MBP0_GTL_N
R23  Q_RES  100 1% CHIP  pkg 0402LF  page 16 : 1 = DBP_CPU0_MBP1_GTL_R_N ; 2 = DBP_CPU_MBP1_GTL_N
R24  Q_RES  10 1% CHIP  pkg 0402LF  page 16 : 1 = DBP_CPU0_HOOK8_MBP2_GTL_QS_R_N ; 2 = DBP_CPU_HOOK8_MBP2_GTL_QS_N
R25  Q_RES  10 1% CHIP  pkg 0402LF  page 16 : 1 = DBP_CPU0_HOOK9_MBP3_GTL_QS_R_N ; 2 = DBP_CPU_HOOK9_MBP3_GTL_QS_N
R26  Q_RES  10K 1% CHIP  pkg 0402LF  page 82 : 1 = PD_CHA_CPU0_DIMM1_SAA ; 2 = GND
R27  Q_RES  15.4K 1% CHIP  pkg 0402LF  page 83 : 1 = PD_CHA_CPU0_DIMM2_SAA ; 2 = GND
R28  Q_RES  23.2K 1% CHIP  pkg 0402LF  page 84 : 1 = PD_CHB_CPU0_DIMM1_SAA ; 2 = GND
R29  Q_RES  35.7K 1% CHIP  pkg 0402LF  page 85 : 1 = PD_CHB_CPU0_DIMM2_SAA ; 2 = GND
R30  Q_RES  54.9K 1% CHIP  pkg 0402LF  page 86 : 1 = PD_CHC_CPU0_DIMM1_SAA ; 2 = GND
R31  Q_RES  84.5K 1% CHIP  pkg 0402LF  page 87 : 1 = PD_CHC_CPU0_DIMM2_SAA ; 2 = GND
R32  Q_RES  127K 1% CHIP  pkg 0402LF  page 88 : 1 = PD_CHD_CPU0_DIMM1_SAA ; 2 = GND
R33  Q_RES  196K 1% CHIP  pkg 0402LF  page 89 : 1 = PD_CHD_CPU0_DIMM2_SAA ; 2 = GND
R34  Q_RES  10K 1% CHIP  pkg 0402LF  page 90 : 1 = PD_CHE_CPU0_DIMM1_SAA ; 2 = GND
R35  Q_RES  15.4K 1% CHIP  pkg 0402LF  page 91 : 1 = PD_CHE_CPU0_DIMM2_SAA ; 2 = GND
R36  Q_RES  23.2K 1% CHIP  pkg 0402LF  page 92 : 1 = PD_CHF_CPU0_DIMM1_SAA ; 2 = GND
R37  Q_RES  35.7K 1% CHIP  pkg 0402LF  page 93 : 1 = PD_CHF_CPU0_DIMM2_SAA ; 2 = GND
R38  Q_RES  54.9K 1% CHIP  pkg 0402LF  page 94 : 1 = PD_CHG_CPU0_DIMM1_SAA ; 2 = GND
R39  Q_RES  84.5K 1% CHIP  pkg 0402LF  page 95 : 1 = PD_CHG_CPU0_DIMM2_SAA ; 2 = GND
R40  Q_RES  127K 1% CHIP  pkg 0402LF  page 96 : 1 = PD_CHH_CPU0_DIMM1_SAA ; 2 = GND
R41  Q_RES  196K 1% CHIP  pkg 0402LF  page 97 : 1 = PD_CHH_CPU0_DIMM2_SAA ; 2 = GND
R42  Q_RES  10K 1% CHIP  pkg 0402LF  page 98 : 1 = PD_CHA_CPU1_DIMM1_SAA ; 2 = GND
R43  Q_RES  15.4K 1% CHIP  pkg 0402LF  page 99 : 1 = PD_CHA_CPU1_DIMM2_SAA ; 2 = GND
R44  Q_RES  23.2K 1% CHIP  pkg 0402LF  page 100 : 1 = PD_CHB_CPU1_DIMM1_SAA ; 2 = GND
R45  Q_RES  35.7K 1% CHIP  pkg 0402LF  page 101 : 1 = PD_CHB_CPU1_DIMM2_SAA ; 2 = GND
R46  Q_RES  54.9K 1% CHIP  pkg 0402LF  page 102 : 1 = PD_CHC_CPU1_DIMM1_SAA ; 2 = GND
R47  Q_RES  84.5K 1% CHIP  pkg 0402LF  page 103 : 1 = PD_CHC_CPU1_DIMM2_SAA ; 2 = GND
R48  Q_RES  127K 1% CHIP  pkg 0402LF  page 104 : 1 = PD_CHD_CPU1_DIMM1_SAA ; 2 = GND
R49  Q_RES  499 1% CHIP  pkg 0402LF  page 47 : 1 = PVNN_TERM_CPU1 ; 2 = DBP_CPU_MBP0_GTL_N
R50  Q_RES  499 1% CHIP  pkg 0402LF  page 47 : 1 = PVNN_TERM_CPU1 ; 2 = DBP_CPU_MBP1_GTL_N
R51  Q_RES  100 1% CHIP  pkg 0402LF  page 47 : 1 = DBP_CPU1_MBP0_GTL_R_N ; 2 = DBP_CPU_MBP0_GTL_N
R52  Q_RES  100 1% CHIP  pkg 0402LF  page 47 : 1 = DBP_CPU1_MBP1_GTL_R_N ; 2 = DBP_CPU_MBP1_GTL_N
R53  Q_RES  10 1% CHIP  pkg 0402LF  page 47 : 1 = DBP_CPU1_HOOK8_MBP2_GTL_QS_R_N ; 2 = DBP_CPU_HOOK8_MBP2_GTL_QS_N
R54  Q_RES  10 1% CHIP  pkg 0402LF  page 47 : 1 = DBP_CPU1_HOOK9_MBP3_GTL_QS_R_N ; 2 = DBP_CPU_HOOK9_MBP3_GTL_QS_N
R55  Q_RES  0 5% CHIP  pkg 0402LF  page 45 : 1 = SVID_DIO0_CPU1 ; 2 = SVID_DIO0_CPU1_R
R56  Q_RES  0 5% CHIP  pkg 0402LF  page 45 : 1 = SVID_CLK0_CPU1 ; 2 = SVID_CLK0_CPU1_R
R57  Q_RES  200 1% CHIP  pkg 0402LF  page 45 : 1 = SVID_ALERT0_CPU1_N ; 2 = SVID_ALERT0_CPU1_R_N
R58  Q_RES  0 5% CHIP  pkg 0402LF  page 45 : 1 = SVID_DIO1_CPU1 ; 2 = SVID_DIO1_CPU1_R
R59  Q_RES  0 5% CHIP  pkg 0402LF  page 45 : 1 = SVID_CLK1_CPU1 ; 2 = SVID_CLK1_CPU1_R
R60  Q_RES  200 1% CHIP  pkg 0402LF  page 45 : 1 = SVID_ALERT1_CPU1_N ; 2 = SVID_ALERT1_CPU1_R_N
R61  Q_RES  10 1% CHIP  pkg 0402LF  page 44 : 1 = H_CPU_PRDY_QS_GTL_N ; 2 = H_CPU1_PRDY_QS_GTL_R_N
R62  Q_RES  100 1% CHIP  pkg 0402LF  page 44 : 1 = H_CPU_PREQ_QS_GTL_N ; 2 = H_CPU1_PREQ_QS_GTL_R_N
R63  Q_RES  33.2 1% CHIP  pkg 0402LF  page 44 : 1 = PECI_CPU_GTL ; 2 = PECI_CPU1_GTL_R
R64  Q_RES  200 1% CHIP  pkg 0402LF  page 44 : 1 = JTAG_MUX_CPU1_GTL_TDI ; 2 = JTAG_DBP_CPU1_GTL_R_TDI
R65  Q_RES  100 1% CHIP  pkg 0402LF  page 44 : 1 = JTAG_DBP_CPU_GTL_TCK ; 2 = JTAG_DBP_CPU1_GTL_R_TCK
R66  Q_RES  100 1% CHIP  pkg 0402LF  page 44 : 1 = JTAG_DBP_CPU_QS_GTL_TMS ; 2 = JTAG_DBP_CPU1_QS_GTL_R_TMS
R67  Q_RES  33.2 1% CHIP  pkg 0402LF  page 43 : 1 = PWRGD_PLT_AUX_CPU0_LVT3_R ; 2 = PWRGD_PLT_AUX_CPU0_LVT3
R68  Q_RES  33.2 1% CHIP  pkg 0402LF  page 43 : 1 = PWRGD_PLT_AUX_CPU1_LVT3_R ; 2 = PWRGD_PLT_AUX_CPU1_LVT3
R69  Q_RES  10K 1% CHIP  pkg 0402LF  page 43 : 1 = PWRGD_PLT_AUX_CPU0_LVT3 ; 2 = GND
R70  Q_RES  10K 1% CHIP  pkg 0402LF  page 43 : 1 = PWRGD_PLT_AUX_CPU1_LVT3 ; 2 = GND
R71  Q_RES  10K 1% CHIP  pkg 0402LF  page 204 : 1 = P3V3_AUX ; 2 = FM_ME_BT_DONE
R72  Q_RES  196K 1% CHIP  pkg 0402LF  page 113 : 1 = PD_CHH_CPU1_DIMM2_SAA ; 2 = GND
R73  Q_RES  127K 1% CHIP  pkg 0402LF  page 112 : 1 = PD_CHH_CPU1_DIMM1_SAA ; 2 = GND
R74  Q_RES  84.5K 1% CHIP  pkg 0402LF  page 111 : 1 = PD_CHG_CPU1_DIMM2_SAA ; 2 = GND
R75  Q_RES  54.9K 1% CHIP  pkg 0402LF  page 110 : 1 = PD_CHG_CPU1_DIMM1_SAA ; 2 = GND
R76  Q_RES  35.7K 1% CHIP  pkg 0402LF  page 109 : 1 = PD_CHF_CPU1_DIMM2_SAA ; 2 = GND
R77  Q_RES  23.2K 1% CHIP  pkg 0402LF  page 108 : 1 = PD_CHF_CPU1_DIMM1_SAA ; 2 = GND
R78  Q_RES  15.4K 1% CHIP  pkg 0402LF  page 107 : 1 = PD_CHE_CPU1_DIMM2_SAA ; 2 = GND
R79  Q_RES  10K 1% CHIP  pkg 0402LF  page 106 : 1 = PD_CHE_CPU1_DIMM1_SAA ; 2 = GND
R80  Q_RES  196K 1% CHIP  pkg 0402LF  page 105 : 1 = PD_CHD_CPU1_DIMM2_SAA ; 2 = GND
R87  Q_RES  1K 1% EMPTY  pkg 0402LF  page 229 : 1 = P3V3_AUX ; 2 = FM_SPD_REMOTE_EN
R90  Q_RES  240 1% EMPTY  pkg 0402LF  page 126 : 1 = PVNN_TERM_CPU1 ; 2 = PU_CPU1_UPI0_AC_COUPLING
R91  Q_RES  240 1% EMPTY  pkg 0402LF  page 126 : 1 = PVNN_TERM_CPU1 ; 2 = PU_CPU1_UPI1_AC_COUPLING
R92  Q_RES  240 1% EMPTY  pkg 0402LF  page 126 : 1 = PVNN_TERM_CPU1 ; 2 = PU_CPU1_UPI2_AC_COUPLING
R93  Q_RES  240 1% EMPTY  pkg 0402LF  page 126 : 1 = PVNN_TERM_CPU1 ; 2 = PU_CPU1_UPI3_AC_COUPLING
R94  Q_RES  240 1% EMPTY  pkg 0402LF  page 126 : 1 = PVNN_TERM_CPU0 ; 2 = PU_CPU0_UPI0_AC_COUPLING
R95  Q_RES  240 1% EMPTY  pkg 0402LF  page 126 : 1 = PVNN_TERM_CPU0 ; 2 = PU_CPU0_UPI1_AC_COUPLING
R96  Q_RES  240 1% EMPTY  pkg 0402LF  page 126 : 1 = PVNN_TERM_CPU0 ; 2 = PU_CPU0_UPI2_AC_COUPLING
R97  Q_RES  240 1% EMPTY  pkg 0402LF  page 126 : 1 = PVNN_TERM_CPU0 ; 2 = PU_CPU0_UPI3_AC_COUPLING
R106  Q_RES  2K 1% CHIP  pkg 0402LF  page 206 : 1 = GND ; 2 = FM_PLD_CLKS_DEV_EN
R107  Q_RES  33.2 1% CHIP  pkg 0402LF  page 241 : 1 = SMB_HOST_3V3AUX_SCL_R ; 2 = SMB_HOST_CLK_BUF_3V3AUX_SCL
R108  Q_RES  33.2 1% CHIP  pkg 0402LF  page 241 : 1 = SMB_HOST_3V3AUX_SDA_R ; 2 = SMB_HOST_CLK_BUF_3V3AUX_SDA
R109  Q_RES  33.2 1% CHIP  pkg 0402LF  page 223 : 1 = FM_PLD_CLK_25M_R_EN ; 2 = FM_PLD_CLK_25M_EN
R110  Q_RES  33.2 1% CHIP  pkg 0402LF  page 223 : 1 = FM_PLD_CLKS_DEV_R_EN ; 2 = FM_PLD_CLKS_DEV_EN
R111  Q_RES  10K 1% CHIP  pkg 0402LF  page 223 : 1 = P3V3 ; 2 = FM_PLD_CLKS_OE_R_N
R113  Q_RES  33.2 1% CHIP  pkg 0402LF  page 223 : 1 = FM_PLD_CLKS_OE_R_N ; 2 = FM_DB2000_OE_N
R120  Q_RES  10M 1% CHIP  pkg 0603LF  page 179 : 1 = XTAL_PCH_RTC2_R ; 2 = XTAL_PCH_RTC1
R122  Q_RES  0 5% CHIP  pkg 0402LF  page 125 : 1 = PWRGD_DRAMPWRGD_CPU1_AB_R_LVC1 ; 2 = PWRGD_DRAMPWRGD_CPU1_AB_LVC1_R2
R124  Q_RES  0 5% CHIP  pkg 0402LF  page 125 : 1 = PWRGD_DRAMPWRGD_CPU1_CD_R_LVC1 ; 2 = PWRGD_DRAMPWRGD_CPU1_CD_LVC1_R2
R126  Q_RES  0 5% CHIP  pkg 0402LF  page 125 : 1 = PWRGD_DRAMPWRGD_CPU1_EF_R_LVC1 ; 2 = PWRGD_DRAMPWRGD_CPU1_EF_LVC1_R2
R128  Q_RES  0 5% CHIP  pkg 0402LF  page 125 : 1 = PWRGD_DRAMPWRGD_CPU1_GH_R_LVC1 ; 2 = PWRGD_DRAMPWRGD_CPU1_GH_LVC1_R2
R130  Q_RES  0 5% CHIP  pkg 0402LF  page 125 : 1 = PWRGD_CPU1_LVC1_R ; 2 = PWRGD_CPU1_BUF_R
R132  Q_RES  0 5% CHIP  pkg 0402LF  page 125 : 1 = RST_CPU1_LVC1_R_N ; 2 = RST_CPU1_BUF_R_N
R135  Q_RES  100 1% CHIP  pkg 0402LF  page 125 : 1 = PWRGD_DRAMPWRGD_CPU1_AB_LVC1_R2 ; 2 = PVCCD_HV_CPU1
R137  Q_RES  100 1% CHIP  pkg 0402LF  page 125 : 1 = PWRGD_DRAMPWRGD_CPU1_CD_LVC1_R2 ; 2 = PVCCD_HV_CPU1
R139  Q_RES  10K 1% EMPTY  pkg 0402LF  page 220 : 1 = FM_BMC_PWRBTN_N ; 2 = P3V3_AUX
R142  Q_RES  0 5% CHIP  pkg 0402LF  page 240 : 1 = PVNN_TERM_CPU0 ; 2 = PVCCIO_PECI_BMC
R143  Q_RES  49.9 1% CHIP  pkg 0402LF  page 197 : 1 = PECI_PCH ; 2 = PECI_PCH_R
R144  Q_RES  0 5% CHIP  pkg 0402LF  page 197 : 1 = PECI_BMC ; 2 = PECI_BMC_R
R145  Q_RES  4.75K 1% EMPTY  pkg 0402LF  page 197 : 1 = PVNN_TERM_CPU0 ; 2 = PECI_PCH_R
R146  Q_RES  4.75K 1% EMPTY  pkg 0402LF  page 197 : 1 = PVNN_TERM_CPU0 ; 2 = PECI_BMC_R
R147  Q_RES  10K 1% CHIP  pkg 0402LF  page 197 : 1 = PECI_PCH_R ; 2 = GND
R148  Q_RES  10K 1% EMPTY  pkg 0402LF  page 197 : 1 = PECI_BMC_R ; 2 = GND
R149  Q_RES  0 5% CHIP  pkg 0402LF  page 197 : 1 = PECI_PCH_R ; 2 = PECI_PCH_B1
R151  Q_RES  100 1% CHIP  pkg 0402LF  page 125 : 1 = PWRGD_DRAMPWRGD_CPU1_EF_LVC1_R2 ; 2 = PVCCD_HV_CPU1
R153  Q_RES  100 1% CHIP  pkg 0402LF  page 125 : 1 = PWRGD_DRAMPWRGD_CPU1_GH_LVC1_R2 ; 2 = PVCCD_HV_CPU1
R155  Q_RES  100 1% CHIP  pkg 0402LF  page 125 : 1 = PWRGD_CPU1_BUF_R ; 2 = PVNN_TERM_CPU1
R156  Q_RES  100 1% CHIP  pkg 0402LF  page 125 : 1 = PWRGD_CPU1_BUF_R ; 2 = PWRGD_CPU1_LVC1
R157  Q_RES  100 1% CHIP  pkg 0402LF  page 125 : 1 = RST_CPU1_BUF_R_N ; 2 = PVNN_TERM_CPU1
R158  Q_RES  100 1% CHIP  pkg 0402LF  page 125 : 1 = RST_CPU1_BUF_R_N ; 2 = RST_CPU1_LVC1_N
